(kicad_pcb
	(version 20260206)
	(generator "pcbnew")
	(generator_version "10.0")
	(general
		(thickness 1.6)
		(legacy_teardrops no)
	)
	(paper "A4")
	(title_block
		(title "12092022_DA0F0TMDCD0_F0T_Management_Board_D_brd_V3_OCP.brd")
		(comment 1 "Grand Teton / footprints 563-568 of 1440")
	)
	(layers
		(0 "F.Cu" signal "TOP")
		(4 "In1.Cu" signal "GND")
		(6 "In2.Cu" signal "IN1")
		(8 "In3.Cu" signal "GND1")
		(10 "In4.Cu" signal "IN2")
		(12 "In5.Cu" signal "VCC")
		(14 "In6.Cu" signal "VCC1")
		(16 "In7.Cu" signal "IN3")
		(18 "In8.Cu" signal "GND2")
		(20 "In9.Cu" signal "IN4")
		(22 "In10.Cu" signal "GND3")
		(2 "B.Cu" signal "BOTTOM")
		(9 "F.Adhes" user "F.Adhesive")
		(11 "B.Adhes" user "B.Adhesive")
		(13 "F.Paste" user "Package Geometry/Pastemask Top")
		(15 "B.Paste" user "Package Geometry/Pastemask Bottom")
		(5 "F.SilkS" user "Ref Des/Silkscreen Top")
		(7 "B.SilkS" user "Ref Des/Silkscreen Bottom")
		(1 "F.Mask" user "Board Geometry/Soldermask Top")
		(3 "B.Mask" user "Board Geometry/Soldermask Bottom")
		(17 "Dwgs.User" user "User.Drawings")
		(19 "Cmts.User" user "User.Comments")
		(21 "Eco1.User" user "User.Eco1")
		(23 "Eco2.User" user "User.Eco2")
		(25 "Edge.Cuts" user "Board Geometry/Outline")
		(27 "Margin" user)
		(31 "F.CrtYd" user "Package Geometry/Place Bound Top")
		(29 "B.CrtYd" user "Package Geometry/Place Bound Bottom")
		(35 "F.Fab" user "Ref Des/Assembly Top")
		(33 "B.Fab" user "Ref Des/Assembly Bottom")
	)
	(footprint ""
		(layer "F.Cu")
		(at 84.201 -93.345)
		(property "Reference" "R110"
			(at 0 0 0)
			(layer "F.SilkS")
			(hide yes)
			(effects
				(font
					(size 1.27 1.27)
				)
			)
		)
		(property "Value" ""
			(at 0 0 0)
			(layer "F.Fab")
			(effects
				(font
					(size 1.27 1.27)
				)
			)
		)
		(duplicate_pad_numbers_are_jumpers no)
		(fp_line
			(start -0.7874 -0.4064)
			(end 0.7874 -0.4064)
			(stroke
				(width 0.1524)
				(type default)
			)
			(layer "F.SilkS")
		)
		(fp_line
			(start -0.7874 0.4064)
			(end -0.7874 -0.4064)
			(stroke
				(width 0.1524)
				(type default)
			)
			(layer "F.SilkS")
		)
		(fp_line
			(start 0.7874 -0.4064)
			(end 0.7874 0.4064)
			(stroke
				(width 0.1524)
				(type default)
			)
			(layer "F.SilkS")
		)
		(fp_line
			(start 0.7874 0.4064)
			(end -0.7874 0.4064)
			(stroke
				(width 0.1524)
				(type default)
			)
			(layer "F.SilkS")
		)
		(fp_line
			(start -0.67945 -0.305054)
			(end -0.12065 -0.305054)
			(stroke
				(width 0.1)
				(type default)
			)
			(layer "F.Fab")
		)
		(fp_line
			(start -0.67945 0.3048)
			(end -0.67945 -0.305054)
			(stroke
				(width 0.1)
				(type default)
			)
			(layer "F.Fab")
		)
		(fp_line
			(start -0.12065 -0.305054)
			(end -0.12065 -0.2794)
			(stroke
				(width 0.1)
				(type default)
			)
			(layer "F.Fab")
		)
		(fp_line
			(start -0.12065 -0.2794)
			(end 0.12065 -0.2794)
			(stroke
				(width 0.1)
				(type default)
			)
			(layer "F.Fab")
		)
		(fp_line
			(start -0.12065 0.2794)
			(end -0.12065 0.3048)
			(stroke
				(width 0.1)
				(type default)
			)
			(layer "F.Fab")
		)
		(fp_line
			(start -0.12065 0.3048)
			(end -0.67945 0.3048)
			(stroke
				(width 0.1)
				(type default)
			)
			(layer "F.Fab")
		)
		(fp_line
			(start 0.120396 0.2794)
			(end -0.12065 0.2794)
			(stroke
				(width 0.1)
				(type default)
			)
			(layer "F.Fab")
		)
		(fp_line
			(start 0.120396 0.3048)
			(end 0.120396 0.2794)
			(stroke
				(width 0.1)
				(type default)
			)
			(layer "F.Fab")
		)
		(fp_line
			(start 0.12065 -0.3048)
			(end 0.67945 -0.3048)
			(stroke
				(width 0.1)
				(type default)
			)
			(layer "F.Fab")
		)
		(fp_line
			(start 0.12065 -0.2794)
			(end 0.12065 -0.3048)
			(stroke
				(width 0.1)
				(type default)
			)
			(layer "F.Fab")
		)
		(fp_line
			(start 0.67945 -0.3048)
			(end 0.67945 0.3048)
			(stroke
				(width 0.1)
				(type default)
			)
			(layer "F.Fab")
		)
		(fp_line
			(start 0.67945 0.3048)
			(end 0.120396 0.3048)
			(stroke
				(width 0.1)
				(type default)
			)
			(layer "F.Fab")
		)
		(pad "1" smd circle
			(at -0.40005 0)
			(size 0 0)
			(layers "F.Cu" "F.Mask" "F.Paste")
			(net "RST_BMC_EXTRST_R3_N")
		)
		(pad "2" smd circle
			(at 0.40005 0)
			(size 0 0)
			(layers "F.Cu" "F.Mask" "F.Paste")
			(net "RST_BMC_EXTRST_R2_N")
		)
	)
	(footprint ""
		(layer "F.Cu")
		(at 14.1732 -83.693 90)
		(property "Reference" "R434"
			(at 0 0 90)
			(layer "F.SilkS")
			(hide yes)
			(effects
				(font
					(size 1.27 1.27)
				)
			)
		)
		(property "Value" ""
			(at 0 0 90)
			(layer "F.Fab")
			(effects
				(font
					(size 1.27 1.27)
				)
			)
		)
		(duplicate_pad_numbers_are_jumpers no)
		(fp_line
			(start 0.7874 -0.4064)
			(end 0.7874 0.4064)
			(stroke
				(width 0.1524)
				(type default)
			)
			(layer "F.SilkS")
		)
		(fp_line
			(start -0.7874 -0.4064)
			(end 0.7874 -0.4064)
			(stroke
				(width 0.1524)
				(type default)
			)
			(layer "F.SilkS")
		)
		(fp_line
			(start 0.7874 0.4064)
			(end -0.7874 0.4064)
			(stroke
				(width 0.1524)
				(type default)
			)
			(layer "F.SilkS")
		)
		(fp_line
			(start -0.7874 0.4064)
			(end -0.7874 -0.4064)
			(stroke
				(width 0.1524)
				(type default)
			)
			(layer "F.SilkS")
		)
		(fp_line
			(start -0.12065 -0.305054)
			(end -0.12065 -0.2794)
			(stroke
				(width 0.1)
				(type default)
			)
			(layer "F.Fab")
		)
		(fp_line
			(start -0.67945 -0.305054)
			(end -0.12065 -0.305054)
			(stroke
				(width 0.1)
				(type default)
			)
			(layer "F.Fab")
		)
		(fp_line
			(start 0.67945 -0.3048)
			(end 0.67945 0.3048)
			(stroke
				(width 0.1)
				(type default)
			)
			(layer "F.Fab")
		)
		(fp_line
			(start 0.12065 -0.3048)
			(end 0.67945 -0.3048)
			(stroke
				(width 0.1)
				(type default)
			)
			(layer "F.Fab")
		)
		(fp_line
			(start 0.12065 -0.2794)
			(end 0.12065 -0.3048)
			(stroke
				(width 0.1)
				(type default)
			)
			(layer "F.Fab")
		)
		(fp_line
			(start -0.12065 -0.2794)
			(end 0.12065 -0.2794)
			(stroke
				(width 0.1)
				(type default)
			)
			(layer "F.Fab")
		)
		(fp_line
			(start 0.120396 0.2794)
			(end -0.12065 0.2794)
			(stroke
				(width 0.1)
				(type default)
			)
			(layer "F.Fab")
		)
		(fp_line
			(start -0.12065 0.2794)
			(end -0.12065 0.3048)
			(stroke
				(width 0.1)
				(type default)
			)
			(layer "F.Fab")
		)
		(fp_line
			(start 0.67945 0.3048)
			(end 0.120396 0.3048)
			(stroke
				(width 0.1)
				(type default)
			)
			(layer "F.Fab")
		)
		(fp_line
			(start 0.120396 0.3048)
			(end 0.120396 0.2794)
			(stroke
				(width 0.1)
				(type default)
			)
			(layer "F.Fab")
		)
		(fp_line
			(start -0.12065 0.3048)
			(end -0.67945 0.3048)
			(stroke
				(width 0.1)
				(type default)
			)
			(layer "F.Fab")
		)
		(fp_line
			(start -0.67945 0.3048)
			(end -0.67945 -0.305054)
			(stroke
				(width 0.1)
				(type default)
			)
			(layer "F.Fab")
		)
		(pad "1" smd circle
			(at -0.40005 0 90)
			(size 0 0)
			(layers "F.Cu" "F.Mask" "F.Paste")
			(net "SGPIO_CLK_PLD_0")
		)
		(pad "2" smd circle
			(at 0.40005 0 90)
			(size 0 0)
			(layers "F.Cu" "F.Mask" "F.Paste")
			(net "SGPIO_CLK_0")
		)
	)
	(footprint ""
		(layer "F.Cu")
		(at 10.3632 -107.95 -90)
		(property "Reference" "R124"
			(at 0 0 270)
			(layer "F.SilkS")
			(hide yes)
			(effects
				(font
					(size 1.27 1.27)
				)
			)
		)
		(property "Value" ""
			(at 0 0 270)
			(layer "F.Fab")
			(effects
				(font
					(size 1.27 1.27)
				)
			)
		)
		(duplicate_pad_numbers_are_jumpers no)
		(fp_line
			(start -0.7874 0.4064)
			(end -0.7874 -0.4064)
			(stroke
				(width 0.1524)
				(type default)
			)
			(layer "F.SilkS")
		)
		(fp_line
			(start 0.7874 0.4064)
			(end -0.7874 0.4064)
			(stroke
				(width 0.1524)
				(type default)
			)
			(layer "F.SilkS")
		)
		(fp_line
			(start -0.7874 -0.4064)
			(end 0.7874 -0.4064)
			(stroke
				(width 0.1524)
				(type default)
			)
			(layer "F.SilkS")
		)
		(fp_line
			(start 0.7874 -0.4064)
			(end 0.7874 0.4064)
			(stroke
				(width 0.1524)
				(type default)
			)
			(layer "F.SilkS")
		)
		(fp_line
			(start -0.67945 0.3048)
			(end -0.67945 -0.305054)
			(stroke
				(width 0.1)
				(type default)
			)
			(layer "F.Fab")
		)
		(fp_line
			(start -0.12065 0.3048)
			(end -0.67945 0.3048)
			(stroke
				(width 0.1)
				(type default)
			)
			(layer "F.Fab")
		)
		(fp_line
			(start 0.120396 0.3048)
			(end 0.120396 0.2794)
			(stroke
				(width 0.1)
				(type default)
			)
			(layer "F.Fab")
		)
		(fp_line
			(start 0.67945 0.3048)
			(end 0.120396 0.3048)
			(stroke
				(width 0.1)
				(type default)
			)
			(layer "F.Fab")
		)
		(fp_line
			(start -0.12065 0.2794)
			(end -0.12065 0.3048)
			(stroke
				(width 0.1)
				(type default)
			)
			(layer "F.Fab")
		)
		(fp_line
			(start 0.120396 0.2794)
			(end -0.12065 0.2794)
			(stroke
				(width 0.1)
				(type default)
			)
			(layer "F.Fab")
		)
		(fp_line
			(start -0.12065 -0.2794)
			(end 0.12065 -0.2794)
			(stroke
				(width 0.1)
				(type default)
			)
			(layer "F.Fab")
		)
		(fp_line
			(start 0.12065 -0.2794)
			(end 0.12065 -0.3048)
			(stroke
				(width 0.1)
				(type default)
			)
			(layer "F.Fab")
		)
		(fp_line
			(start 0.12065 -0.3048)
			(end 0.67945 -0.3048)
			(stroke
				(width 0.1)
				(type default)
			)
			(layer "F.Fab")
		)
		(fp_line
			(start 0.67945 -0.3048)
			(end 0.67945 0.3048)
			(stroke
				(width 0.1)
				(type default)
			)
			(layer "F.Fab")
		)
		(fp_line
			(start -0.67945 -0.305054)
			(end -0.12065 -0.305054)
			(stroke
				(width 0.1)
				(type default)
			)
			(layer "F.Fab")
		)
		(fp_line
			(start -0.12065 -0.305054)
			(end -0.12065 -0.2794)
			(stroke
				(width 0.1)
				(type default)
			)
			(layer "F.Fab")
		)
		(pad "1" smd circle
			(at -0.40005 0 270)
			(size 0 0)
			(layers "F.Cu" "F.Mask" "F.Paste")
			(net "P3V3_AUX")
		)
		(pad "2" smd circle
			(at 0.40005 0 270)
			(size 0 0)
			(layers "F.Cu" "F.Mask" "F.Paste")
			(net "RST_BMC_SRST_BUF_R_N")
		)
	)
	(footprint ""
		(layer "F.Cu")
		(at 68.072 -108.0262 90)
		(property "Reference" "R823"
			(at 0 0 90)
			(layer "F.SilkS")
			(hide yes)
			(effects
				(font
					(size 1.27 1.27)
				)
			)
		)
		(property "Value" ""
			(at 0 0 90)
			(layer "F.Fab")
			(effects
				(font
					(size 1.27 1.27)
				)
			)
		)
		(duplicate_pad_numbers_are_jumpers no)
		(fp_line
			(start 0.7874 -0.4064)
			(end 0.7874 0.4064)
			(stroke
				(width 0.1524)
				(type default)
			)
			(layer "F.SilkS")
		)
		(fp_line
			(start -0.7874 -0.4064)
			(end 0.7874 -0.4064)
			(stroke
				(width 0.1524)
				(type default)
			)
			(layer "F.SilkS")
		)
		(fp_line
			(start 0.7874 0.4064)
			(end -0.7874 0.4064)
			(stroke
				(width 0.1524)
				(type default)
			)
			(layer "F.SilkS")
		)
		(fp_line
			(start -0.7874 0.4064)
			(end -0.7874 -0.4064)
			(stroke
				(width 0.1524)
				(type default)
			)
			(layer "F.SilkS")
		)
		(fp_line
			(start -0.12065 -0.305054)
			(end -0.12065 -0.2794)
			(stroke
				(width 0.1)
				(type default)
			)
			(layer "F.Fab")
		)
		(fp_line
			(start -0.67945 -0.305054)
			(end -0.12065 -0.305054)
			(stroke
				(width 0.1)
				(type default)
			)
			(layer "F.Fab")
		)
		(fp_line
			(start 0.67945 -0.3048)
			(end 0.67945 0.3048)
			(stroke
				(width 0.1)
				(type default)
			)
			(layer "F.Fab")
		)
		(fp_line
			(start 0.12065 -0.3048)
			(end 0.67945 -0.3048)
			(stroke
				(width 0.1)
				(type default)
			)
			(layer "F.Fab")
		)
		(fp_line
			(start 0.12065 -0.2794)
			(end 0.12065 -0.3048)
			(stroke
				(width 0.1)
				(type default)
			)
			(layer "F.Fab")
		)
		(fp_line
			(start -0.12065 -0.2794)
			(end 0.12065 -0.2794)
			(stroke
				(width 0.1)
				(type default)
			)
			(layer "F.Fab")
		)
		(fp_line
			(start 0.120396 0.2794)
			(end -0.12065 0.2794)
			(stroke
				(width 0.1)
				(type default)
			)
			(layer "F.Fab")
		)
		(fp_line
			(start -0.12065 0.2794)
			(end -0.12065 0.3048)
			(stroke
				(width 0.1)
				(type default)
			)
			(layer "F.Fab")
		)
		(fp_line
			(start 0.67945 0.3048)
			(end 0.120396 0.3048)
			(stroke
				(width 0.1)
				(type default)
			)
			(layer "F.Fab")
		)
		(fp_line
			(start 0.120396 0.3048)
			(end 0.120396 0.2794)
			(stroke
				(width 0.1)
				(type default)
			)
			(layer "F.Fab")
		)
		(fp_line
			(start -0.12065 0.3048)
			(end -0.67945 0.3048)
			(stroke
				(width 0.1)
				(type default)
			)
			(layer "F.Fab")
		)
		(fp_line
			(start -0.67945 0.3048)
			(end -0.67945 -0.305054)
			(stroke
				(width 0.1)
				(type default)
			)
			(layer "F.Fab")
		)
		(pad "1" smd circle
			(at -0.40005 0 90)
			(size 0 0)
			(layers "F.Cu" "F.Mask" "F.Paste")
			(net "GND")
		)
		(pad "2" smd circle
			(at 0.40005 0 90)
			(size 0 0)
			(layers "F.Cu" "F.Mask" "F.Paste")
			(net "FM_VIRTUAL_RESEAT")
		)
	)
	(footprint ""
		(layer "F.Cu")
		(at 53.213 -69.723 90)
		(property "Reference" "R682"
			(at 0 0 90)
			(layer "F.SilkS")
			(hide yes)
			(effects
				(font
					(size 1.27 1.27)
				)
			)
		)
		(property "Value" ""
			(at 0 0 90)
			(layer "F.Fab")
			(effects
				(font
					(size 1.27 1.27)
				)
			)
		)
		(duplicate_pad_numbers_are_jumpers no)
		(fp_line
			(start 0.7874 -0.4064)
			(end 0.7874 0.4064)
			(stroke
				(width 0.1524)
				(type default)
			)
			(layer "F.SilkS")
		)
		(fp_line
			(start -0.7874 -0.4064)
			(end 0.7874 -0.4064)
			(stroke
				(width 0.1524)
				(type default)
			)
			(layer "F.SilkS")
		)
		(fp_line
			(start 0.7874 0.4064)
			(end -0.7874 0.4064)
			(stroke
				(width 0.1524)
				(type default)
			)
			(layer "F.SilkS")
		)
		(fp_line
			(start -0.7874 0.4064)
			(end -0.7874 -0.4064)
			(stroke
				(width 0.1524)
				(type default)
			)
			(layer "F.SilkS")
		)
		(fp_line
			(start -0.12065 -0.305054)
			(end -0.12065 -0.2794)
			(stroke
				(width 0.1)
				(type default)
			)
			(layer "F.Fab")
		)
		(fp_line
			(start -0.67945 -0.305054)
			(end -0.12065 -0.305054)
			(stroke
				(width 0.1)
				(type default)
			)
			(layer "F.Fab")
		)
		(fp_line
			(start 0.67945 -0.3048)
			(end 0.67945 0.3048)
			(stroke
				(width 0.1)
				(type default)
			)
			(layer "F.Fab")
		)
		(fp_line
			(start 0.12065 -0.3048)
			(end 0.67945 -0.3048)
			(stroke
				(width 0.1)
				(type default)
			)
			(layer "F.Fab")
		)
		(fp_line
			(start 0.12065 -0.2794)
			(end 0.12065 -0.3048)
			(stroke
				(width 0.1)
				(type default)
			)
			(layer "F.Fab")
		)
		(fp_line
			(start -0.12065 -0.2794)
			(end 0.12065 -0.2794)
			(stroke
				(width 0.1)
				(type default)
			)
			(layer "F.Fab")
		)
		(fp_line
			(start 0.120396 0.2794)
			(end -0.12065 0.2794)
			(stroke
				(width 0.1)
				(type default)
			)
			(layer "F.Fab")
		)
		(fp_line
			(start -0.12065 0.2794)
			(end -0.12065 0.3048)
			(stroke
				(width 0.1)
				(type default)
			)
			(layer "F.Fab")
		)
		(fp_line
			(start 0.67945 0.3048)
			(end 0.120396 0.3048)
			(stroke
				(width 0.1)
				(type default)
			)
			(layer "F.Fab")
		)
		(fp_line
			(start 0.120396 0.3048)
			(end 0.120396 0.2794)
			(stroke
				(width 0.1)
				(type default)
			)
			(layer "F.Fab")
		)
		(fp_line
			(start -0.12065 0.3048)
			(end -0.67945 0.3048)
			(stroke
				(width 0.1)
				(type default)
			)
			(layer "F.Fab")
		)
		(fp_line
			(start -0.67945 0.3048)
			(end -0.67945 -0.305054)
			(stroke
				(width 0.1)
				(type default)
			)
			(layer "F.Fab")
		)
		(pad "1" smd circle
			(at -0.40005 0 90)
			(size 0 0)
			(layers "F.Cu" "F.Mask" "F.Paste")
			(net "SPI_BMC_IO3_R")
		)
		(pad "2" smd circle
			(at 0.40005 0 90)
			(size 0 0)
			(layers "F.Cu" "F.Mask" "F.Paste")
			(net "QSPI_2_PLD_IO3")
		)
	)
	(footprint ""
		(layer "F.Cu")
		(at 81.755996 -76.258928 180)
		(property "Reference" "PC252"
			(at 0 0 180)
			(layer "F.SilkS")
			(hide yes)
			(effects
				(font
					(size 1.27 1.27)
				)
			)
		)
		(property "Value" ""
			(at 0 0 180)
			(layer "F.Fab")
			(effects
				(font
					(size 1.27 1.27)
				)
			)
		)
		(duplicate_pad_numbers_are_jumpers no)
		(fp_line
			(start 1.651 0.8382)
			(end -1.651 0.8382)
			(stroke
				(width 0.1524)
				(type default)
			)
			(layer "F.SilkS")
		)
		(fp_line
			(start 1.651 -0.8382)
			(end 1.651 0.8382)
			(stroke
				(width 0.1524)
				(type default)
			)
			(layer "F.SilkS")
		)
		(fp_line
			(start 0 0.8382)
			(end 0 -0.8382)
			(stroke
				(width 0.1524)
				(type default)
			)
			(layer "F.SilkS")
		)
		(fp_line
			(start -1.651 0.8382)
			(end -1.651 -0.8382)
			(stroke
				(width 0.1524)
				(type default)
			)
			(layer "F.SilkS")
		)
		(fp_line
			(start -1.651 -0.8382)
			(end 1.651 -0.8382)
			(stroke
				(width 0.1524)
				(type default)
			)
			(layer "F.SilkS")
		)
		(fp_line
			(start 1.55956 0.7366)
			(end 1.55956 -0.7366)
			(stroke
				(width 0.1)
				(type default)
			)
			(layer "F.Fab")
		)
		(fp_line
			(start 1.55956 -0.7366)
			(end 1.524 -0.7366)
			(stroke
				(width 0.1)
				(type default)
			)
			(layer "F.Fab")
		)
		(fp_line
			(start 1.524 0.7366)
			(end 1.55956 0.7366)
			(stroke
				(width 0.1)
				(type default)
			)
			(layer "F.Fab")
		)
		(fp_line
			(start 1.524 -0.7366)
			(end -1.524 -0.7366)
			(stroke
				(width 0.1)
				(type default)
			)
			(layer "F.Fab")
		)
		(fp_line
			(start -1.524 0.7366)
			(end 1.524 0.7366)
			(stroke
				(width 0.1)
				(type default)
			)
			(layer "F.Fab")
		)
		(fp_line
			(start -1.524 -0.7366)
			(end -1.55956 -0.7366)
			(stroke
				(width 0.1)
				(type default)
			)
			(layer "F.Fab")
		)
		(fp_line
			(start -1.55956 0.7366)
			(end -1.524 0.7366)
			(stroke
				(width 0.1)
				(type default)
			)
			(layer "F.Fab")
		)
		(fp_line
			(start -1.55956 -0.7366)
			(end -1.55956 0.7366)
			(stroke
				(width 0.1)
				(type default)
			)
			(layer "F.Fab")
		)
		(pad "1" smd rect
			(at -0.94996 0)
			(size 1.1176 1.3716)
			(layers "F.Cu" "F.Mask" "F.Paste")
			(net "SW_P1V2_AUX_FLT")
		)
		(pad "2" smd rect
			(at 0.94996 0)
			(size 1.1176 1.3716)
			(layers "F.Cu" "F.Mask" "F.Paste")
			(net "GND")
		)
	)
)
